(kicad_pcb
	(version 20260206)
	(generator "pcbnew")
	(generator_version "10.0")
	(general
		(thickness 1.6)
		(legacy_teardrops no)
	)
	(paper "A4")
	(title_block
		(title "Bryce Canyon_R.DPB_16317-1_OCP.brd")
		(comment 1 "Bryce Canyon / footprints 15-22 of 2099")
	)
	(layers
		(0 "F.Cu" signal "TOP")
		(4 "In1.Cu" signal "L2GND")
		(6 "In2.Cu" signal "L3")
		(8 "In3.Cu" signal "L4VCC")
		(10 "In4.Cu" signal "L5VCC")
		(12 "In5.Cu" signal "L6")
		(14 "In6.Cu" signal "L7GND")
		(2 "B.Cu" signal "BOTTOM")
		(9 "F.Adhes" user "F.Adhesive")
		(11 "B.Adhes" user "B.Adhesive")
		(13 "F.Paste" user "Package Geometry/Pastemask Top")
		(15 "B.Paste" user "Package Geometry/Pastemask Bottom")
		(5 "F.SilkS" user "Ref Des/Silkscreen Top")
		(7 "B.SilkS" user "Ref Des/Silkscreen Bottom")
		(1 "F.Mask" user "Board Geometry/Soldermask Top")
		(3 "B.Mask" user "Board Geometry/Soldermask Bottom")
		(17 "Dwgs.User" user "User.Drawings")
		(19 "Cmts.User" user "User.Comments")
		(21 "Eco1.User" user "User.Eco1")
		(23 "Eco2.User" user "User.Eco2")
		(25 "Edge.Cuts" user "Board Geometry/Outline")
		(27 "Margin" user)
		(31 "F.CrtYd" user "Package Geometry/Place Bound Top")
		(29 "B.CrtYd" user "Package Geometry/Place Bound Bottom")
		(35 "F.Fab" user "Ref Des/Assembly Top")
		(33 "B.Fab" user "Ref Des/Assembly Bottom")
	)
	(footprint ""
		(layer "F.Cu")
		(at 463.404712 -221.75089 -90)
		(property "Reference" "C662"
			(at 0 0 270)
			(layer "F.SilkS")
			(hide yes)
			(effects
				(font
					(size 1.27 1.27)
				)
			)
		)
		(property "Value" "SC2200P50V2KX-2GP"
			(at 1.1811 -2.7051 270)
			(unlocked yes)
			(layer "F.Fab")
			(hide yes)
			(effects
				(font
					(size 1.016 1.016)
					(thickness 0.1524)
				)
			)
		)
		(property "Device Type" "C402H22"
			(at 1.1811 -4.2291 270)
			(unlocked yes)
			(layer "F.Fab")
			(hide yes)
			(effects
				(font
					(size 1.016 1.016)
					(thickness 0.1524)
				)
			)
		)
		(duplicate_pad_numbers_are_jumpers no)
		(fp_rect
			(start -0.4318 0.9525)
			(end 0.4318 -0.9525)
			(stroke
				(width 0)
				(type default)
			)
			(fill no)
			(layer "F.CrtYd")
		)
		(fp_rect
			(start -0.4318 0.9525)
			(end 0.4318 -0.9525)
			(stroke
				(width 0)
				(type default)
			)
			(fill no)
			(layer "F.Fab")
		)
		(pad "1" smd custom
			(at 0 -0.4445 270)
			(size 0.1524 0.1524)
			(layers "F.Cu" "F.Mask" "F.Paste")
			(net "P5V_B_3_LL")
			(options
				(clearance outline)
				(anchor circle)
			)
			(primitives
				(gr_poly
					(pts
						(arc
							(start 0.3048 -0.2032)
							(mid 0.275042 -0.275042)
							(end 0.2032 -0.3048)
						)
						(arc
							(start -0.2032 -0.3048)
							(mid -0.275042 -0.275042)
							(end -0.3048 -0.2032)
						)
						(arc
							(start -0.3048 0.2032)
							(mid -0.275042 0.275042)
							(end -0.2032 0.3048)
						)
						(arc
							(start 0.2032 0.3048)
							(mid 0.275042 0.275042)
							(end 0.3048 0.2032)
						)
					)
					(width 0)
					(fill yes)
				)
			)
		)
		(pad "2" smd custom
			(at 0 0.4445 270)
			(size 0.1524 0.1524)
			(layers "F.Cu" "F.Mask" "F.Paste")
			(net "P5V_B_3_SNB")
			(options
				(clearance outline)
				(anchor circle)
			)
			(primitives
				(gr_poly
					(pts
						(arc
							(start 0.3048 -0.2032)
							(mid 0.275042 -0.275042)
							(end 0.2032 -0.3048)
						)
						(arc
							(start -0.2032 -0.3048)
							(mid -0.275042 -0.275042)
							(end -0.3048 -0.2032)
						)
						(arc
							(start -0.3048 0.2032)
							(mid -0.275042 0.275042)
							(end -0.2032 0.3048)
						)
						(arc
							(start 0.2032 0.3048)
							(mid 0.275042 0.275042)
							(end 0.3048 0.2032)
						)
					)
					(width 0)
					(fill yes)
				)
			)
		)
	)
	(footprint ""
		(layer "F.Cu")
		(at 432.689 -20.447 90)
		(property "Reference" "R845"
			(at 0 0 90)
			(layer "F.SilkS")
			(hide yes)
			(effects
				(font
					(size 1.27 1.27)
				)
			)
		)
		(property "Value" "200KR2F-L-GP"
			(at 0.064008 -3.993896 90)
			(unlocked yes)
			(layer "F.Fab")
			(hide yes)
			(effects
				(font
					(size 1.016 1.016)
					(thickness 0.1524)
				)
			)
		)
		(property "Device Type" "R402H16"
			(at 0.064008 -5.517896 90)
			(unlocked yes)
			(layer "F.Fab")
			(hide yes)
			(effects
				(font
					(size 1.016 1.016)
					(thickness 0.1524)
				)
			)
		)
		(duplicate_pad_numbers_are_jumpers no)
		(fp_line
			(start 0.508 -0.9398)
			(end -0.508 -0.9398)
			(stroke
				(width 0.1524)
				(type default)
			)
			(layer "F.SilkS")
		)
		(fp_line
			(start -0.508 -0.9398)
			(end -0.508 0.9398)
			(stroke
				(width 0.1524)
				(type default)
			)
			(layer "F.SilkS")
		)
		(fp_rect
			(start -0.508 0.9398)
			(end 0.508 -0.9398)
			(stroke
				(width 0)
				(type default)
			)
			(fill no)
			(layer "F.CrtYd")
		)
		(fp_rect
			(start -0.508 0.9398)
			(end 0.508 -0.9398)
			(stroke
				(width 0)
				(type default)
			)
			(fill no)
			(layer "F.Fab")
		)
		(pad "1" smd custom
			(at 0 -0.4445 90)
			(size 0.1397 0.1397)
			(layers "F.Cu" "F.Mask" "F.Paste")
			(net "SW_HDD_R33")
			(options
				(clearance outline)
				(anchor circle)
			)
			(primitives
				(gr_poly
					(pts
						(arc
							(start -0.1778 -0.2794)
							(mid -0.249642 -0.249642)
							(end -0.2794 -0.1778)
						)
						(arc
							(start -0.2794 0.1778)
							(mid -0.249642 0.249642)
							(end -0.1778 0.2794)
						)
						(arc
							(start 0.1778 0.2794)
							(mid 0.249642 0.249642)
							(end 0.2794 0.1778)
						)
						(arc
							(start 0.2794 -0.1778)
							(mid 0.249642 -0.249642)
							(end 0.1778 -0.2794)
						)
					)
					(width 0)
					(fill yes)
				)
			)
		)
		(pad "2" smd custom
			(at 0 0.4445 90)
			(size 0.1397 0.1397)
			(layers "F.Cu" "F.Mask" "F.Paste")
			(net "SW_HDD_N33")
			(options
				(clearance outline)
				(anchor circle)
			)
			(primitives
				(gr_poly
					(pts
						(arc
							(start -0.1778 -0.2794)
							(mid -0.249642 -0.249642)
							(end -0.2794 -0.1778)
						)
						(arc
							(start -0.2794 0.1778)
							(mid -0.249642 0.249642)
							(end -0.1778 0.2794)
						)
						(arc
							(start 0.1778 0.2794)
							(mid 0.249642 0.249642)
							(end 0.2794 0.1778)
						)
						(arc
							(start 0.2794 -0.1778)
							(mid 0.249642 -0.249642)
							(end 0.1778 -0.2794)
						)
					)
					(width 0)
					(fill yes)
				)
			)
		)
	)
	(footprint ""
		(layer "F.Cu")
		(at 176.276 -20.955 90)
		(property "Reference" "C415"
			(at 0 0 90)
			(layer "F.SilkS")
			(hide yes)
			(effects
				(font
					(size 1.27 1.27)
				)
			)
		)
		(property "Value" "SCD033U25V2KX-GP"
			(at 1.1811 -2.7051 90)
			(unlocked yes)
			(layer "F.Fab")
			(hide yes)
			(effects
				(font
					(size 1.016 1.016)
					(thickness 0.1524)
				)
			)
		)
		(property "Device Type" "C402H22"
			(at 1.1811 -4.2291 90)
			(unlocked yes)
			(layer "F.Fab")
			(hide yes)
			(effects
				(font
					(size 1.016 1.016)
					(thickness 0.1524)
				)
			)
		)
		(duplicate_pad_numbers_are_jumpers no)
		(fp_rect
			(start -0.4318 0.9525)
			(end 0.4318 -0.9525)
			(stroke
				(width 0)
				(type default)
			)
			(fill no)
			(layer "F.CrtYd")
		)
		(fp_rect
			(start -0.4318 0.9525)
			(end 0.4318 -0.9525)
			(stroke
				(width 0)
				(type default)
			)
			(fill no)
			(layer "F.Fab")
		)
		(pad "1" smd custom
			(at 0 -0.4445 90)
			(size 0.1524 0.1524)
			(layers "F.Cu" "F.Mask" "F.Paste")
			(net "SW_HDD_P29")
			(options
				(clearance outline)
				(anchor circle)
			)
			(primitives
				(gr_poly
					(pts
						(arc
							(start 0.3048 -0.2032)
							(mid 0.275042 -0.275042)
							(end 0.2032 -0.3048)
						)
						(arc
							(start -0.2032 -0.3048)
							(mid -0.275042 -0.275042)
							(end -0.3048 -0.2032)
						)
						(arc
							(start -0.3048 0.2032)
							(mid -0.275042 0.275042)
							(end -0.2032 0.3048)
						)
						(arc
							(start 0.2032 0.3048)
							(mid 0.275042 0.275042)
							(end 0.3048 0.2032)
						)
					)
					(width 0)
					(fill yes)
				)
			)
		)
		(pad "2" smd custom
			(at 0 0.4445 90)
			(size 0.1524 0.1524)
			(layers "F.Cu" "F.Mask" "F.Paste")
			(net "GND")
			(options
				(clearance outline)
				(anchor circle)
			)
			(primitives
				(gr_poly
					(pts
						(arc
							(start 0.3048 -0.2032)
							(mid 0.275042 -0.275042)
							(end 0.2032 -0.3048)
						)
						(arc
							(start -0.2032 -0.3048)
							(mid -0.275042 -0.275042)
							(end -0.3048 -0.2032)
						)
						(arc
							(start -0.3048 0.2032)
							(mid -0.275042 0.275042)
							(end -0.2032 0.3048)
						)
						(arc
							(start 0.2032 0.3048)
							(mid 0.275042 0.275042)
							(end 0.3048 0.2032)
						)
					)
					(width 0)
					(fill yes)
				)
			)
		)
	)
	(footprint ""
		(layer "F.Cu")
		(at 86.868 -148.209)
		(property "Reference" "R391"
			(at 0 0 0)
			(layer "F.SilkS")
			(hide yes)
			(effects
				(font
					(size 1.27 1.27)
				)
			)
		)
		(property "Value" "2R6F-GP"
			(at -0.0508 -4.8514 0)
			(unlocked yes)
			(layer "F.Fab")
			(hide yes)
			(effects
				(font
					(size 1.016 1.016)
					(thickness 0.1524)
				)
			)
		)
		(property "Device Type" "R1206H26"
			(at 0 -6.3754 0)
			(unlocked yes)
			(layer "F.Fab")
			(hide yes)
			(effects
				(font
					(size 1.016 1.016)
					(thickness 0.1524)
				)
			)
		)
		(duplicate_pad_numbers_are_jumpers no)
		(fp_line
			(start -1.016 -2.2352)
			(end 1.016 -2.2352)
			(stroke
				(width 0.1524)
				(type default)
			)
			(layer "F.SilkS")
		)
		(fp_line
			(start -1.016 2.2352)
			(end -1.016 -2.2352)
			(stroke
				(width 0.1524)
				(type default)
			)
			(layer "F.SilkS")
		)
		(fp_line
			(start 1.016 -2.2352)
			(end 1.016 2.2352)
			(stroke
				(width 0.1524)
				(type default)
			)
			(layer "F.SilkS")
		)
		(fp_line
			(start 1.016 2.2352)
			(end -1.016 2.2352)
			(stroke
				(width 0.1524)
				(type default)
			)
			(layer "F.SilkS")
		)
		(fp_rect
			(start -1.0922 2.3114)
			(end 1.0922 -2.3114)
			(stroke
				(width 0)
				(type default)
			)
			(fill no)
			(layer "F.CrtYd")
		)
		(fp_poly
			(pts
				(xy -1.0922 -2.3114) (xy 1.0922 -2.3114) (xy 1.0922 2.3114) (xy -1.0922 2.3114)
			)
			(stroke
				(width 0)
				(type default)
			)
			(fill no)
			(layer "F.Fab")
		)
		(pad "1" smd rect
			(at 0 -1.397)
			(size 1.651 1.27)
			(layers "F.Cu" "F.Mask" "F.Paste")
			(net "P5V_HDD14")
		)
		(pad "2" smd rect
			(at 0 1.397)
			(size 1.651 1.27)
			(layers "F.Cu" "F.Mask" "F.Paste")
			(net "5V_PRE_14")
		)
	)
	(footprint ""
		(layer "F.Cu")
		(at 259.113782 -226.81311 90)
		(property "Reference" "C40"
			(at 0 0 90)
			(layer "F.SilkS")
			(hide yes)
			(effects
				(font
					(size 1.27 1.27)
				)
			)
		)
		(property "Value" "SCD1U16V2KX-3GP"
			(at 1.1811 -2.7051 90)
			(unlocked yes)
			(layer "F.Fab")
			(hide yes)
			(effects
				(font
					(size 1.016 1.016)
					(thickness 0.1524)
				)
			)
		)
		(property "Device Type" "C402H22"
			(at 1.1811 -4.2291 90)
			(unlocked yes)
			(layer "F.Fab")
			(hide yes)
			(effects
				(font
					(size 1.016 1.016)
					(thickness 0.1524)
				)
			)
		)
		(duplicate_pad_numbers_are_jumpers no)
		(fp_rect
			(start -0.4318 0.9525)
			(end 0.4318 -0.9525)
			(stroke
				(width 0)
				(type default)
			)
			(fill no)
			(layer "F.CrtYd")
		)
		(fp_rect
			(start -0.4318 0.9525)
			(end 0.4318 -0.9525)
			(stroke
				(width 0)
				(type default)
			)
			(fill no)
			(layer "F.Fab")
		)
		(pad "1" smd custom
			(at 0 -0.4445 90)
			(size 0.1524 0.1524)
			(layers "F.Cu" "F.Mask" "F.Paste")
			(net "P5V_B_3_SENSE")
			(options
				(clearance outline)
				(anchor circle)
			)
			(primitives
				(gr_poly
					(pts
						(arc
							(start 0.3048 -0.2032)
							(mid 0.275042 -0.275042)
							(end 0.2032 -0.3048)
						)
						(arc
							(start -0.2032 -0.3048)
							(mid -0.275042 -0.275042)
							(end -0.3048 -0.2032)
						)
						(arc
							(start -0.3048 0.2032)
							(mid -0.275042 0.275042)
							(end -0.2032 0.3048)
						)
						(arc
							(start 0.2032 0.3048)
							(mid 0.275042 0.275042)
							(end 0.3048 0.2032)
						)
					)
					(width 0)
					(fill yes)
				)
			)
		)
		(pad "2" smd custom
			(at 0 0.4445 90)
			(size 0.1524 0.1524)
			(layers "F.Cu" "F.Mask" "F.Paste")
			(net "GND")
			(options
				(clearance outline)
				(anchor circle)
			)
			(primitives
				(gr_poly
					(pts
						(arc
							(start 0.3048 -0.2032)
							(mid 0.275042 -0.275042)
							(end 0.2032 -0.3048)
						)
						(arc
							(start -0.2032 -0.3048)
							(mid -0.275042 -0.275042)
							(end -0.3048 -0.2032)
						)
						(arc
							(start -0.3048 0.2032)
							(mid -0.275042 0.275042)
							(end -0.2032 0.3048)
						)
						(arc
							(start 0.2032 0.3048)
							(mid 0.275042 0.275042)
							(end 0.3048 0.2032)
						)
					)
					(width 0)
					(fill yes)
				)
			)
		)
	)
	(footprint ""
		(layer "F.Cu")
		(at 149.1996 -18.4912 -90)
		(property "Reference" "R722"
			(at 0 0 270)
			(layer "F.SilkS")
			(hide yes)
			(effects
				(font
					(size 1.27 1.27)
				)
			)
		)
		(property "Value" "1KR2F-3-GP"
			(at 0.064008 -3.993896 270)
			(unlocked yes)
			(layer "F.Fab")
			(hide yes)
			(effects
				(font
					(size 1.016 1.016)
					(thickness 0.1524)
				)
			)
		)
		(property "Device Type" "R402H16"
			(at 0.064008 -5.517896 270)
			(unlocked yes)
			(layer "F.Fab")
			(hide yes)
			(effects
				(font
					(size 1.016 1.016)
					(thickness 0.1524)
				)
			)
		)
		(duplicate_pad_numbers_are_jumpers no)
		(fp_line
			(start -0.508 -0.9398)
			(end -0.508 0.9398)
			(stroke
				(width 0.1524)
				(type default)
			)
			(layer "F.SilkS")
		)
		(fp_line
			(start 0.508 -0.9398)
			(end -0.508 -0.9398)
			(stroke
				(width 0.1524)
				(type default)
			)
			(layer "F.SilkS")
		)
		(fp_rect
			(start -0.508 0.9398)
			(end 0.508 -0.9398)
			(stroke
				(width 0)
				(type default)
			)
			(fill no)
			(layer "F.CrtYd")
		)
		(fp_rect
			(start -0.508 0.9398)
			(end 0.508 -0.9398)
			(stroke
				(width 0)
				(type default)
			)
			(fill no)
			(layer "F.Fab")
		)
		(pad "1" smd custom
			(at 0 -0.4445 270)
			(size 0.1397 0.1397)
			(layers "F.Cu" "F.Mask" "F.Paste")
			(net "P3V3_STBY_B")
			(options
				(clearance outline)
				(anchor circle)
			)
			(primitives
				(gr_poly
					(pts
						(arc
							(start -0.1778 -0.2794)
							(mid -0.249642 -0.249642)
							(end -0.2794 -0.1778)
						)
						(arc
							(start -0.2794 0.1778)
							(mid -0.249642 0.249642)
							(end -0.1778 0.2794)
						)
						(arc
							(start 0.1778 0.2794)
							(mid 0.249642 0.249642)
							(end 0.2794 0.1778)
						)
						(arc
							(start 0.2794 -0.1778)
							(mid 0.249642 -0.249642)
							(end 0.1778 -0.2794)
						)
					)
					(width 0)
					(fill yes)
				)
			)
		)
		(pad "2" smd custom
			(at 0 0.4445 270)
			(size 0.1397 0.1397)
			(layers "F.Cu" "F.Mask" "F.Paste")
			(net "SW_PWR_R_HDD28")
			(options
				(clearance outline)
				(anchor circle)
			)
			(primitives
				(gr_poly
					(pts
						(arc
							(start -0.1778 -0.2794)
							(mid -0.249642 -0.249642)
							(end -0.2794 -0.1778)
						)
						(arc
							(start -0.2794 0.1778)
							(mid -0.249642 0.249642)
							(end -0.1778 0.2794)
						)
						(arc
							(start 0.1778 0.2794)
							(mid 0.249642 0.249642)
							(end 0.2794 0.1778)
						)
						(arc
							(start 0.2794 -0.1778)
							(mid 0.249642 -0.249642)
							(end 0.1778 -0.2794)
						)
					)
					(width 0)
					(fill yes)
				)
			)
		)
	)
	(footprint ""
		(layer "F.Cu")
		(at 457.581 -160.02 180)
		(property "Reference" "C321"
			(at 0 0 180)
			(layer "F.SilkS")
			(hide yes)
			(effects
				(font
					(size 1.27 1.27)
				)
			)
		)
		(property "Value" "SC4D7U25V5KX-1-GP"
			(at -0.0762 -6.1214 180)
			(unlocked yes)
			(layer "F.Fab")
			(hide yes)
			(effects
				(font
					(size 1.016 1.016)
					(thickness 0.1524)
				)
			)
		)
		(property "Device Type" "C805H58"
			(at -0.0762 -8.1534 180)
			(unlocked yes)
			(layer "F.Fab")
			(hide yes)
			(effects
				(font
					(size 1.016 1.016)
					(thickness 0.1524)
				)
			)
		)
		(duplicate_pad_numbers_are_jumpers no)
		(fp_line
			(start 0.635 0)
			(end -0.635 0)
			(stroke
				(width 0.508)
				(type default)
			)
			(layer "F.SilkS")
		)
		(fp_rect
			(start -0.9652 1.778)
			(end 0.9652 -1.778)
			(stroke
				(width 0)
				(type default)
			)
			(fill no)
			(layer "F.CrtYd")
		)
		(fp_poly
			(pts
				(xy -0.9652 -1.778) (xy 0.9652 -1.778) (xy 0.9652 1.778) (xy -0.9652 1.778)
			)
			(stroke
				(width 0)
				(type default)
			)
			(fill no)
			(layer "F.Fab")
		)
		(pad "1" smd rect
			(at 0 -0.9652 180)
			(size 1.397 1.143)
			(layers "F.Cu" "F.Mask" "F.Paste")
			(net "P12V_HDD22")
		)
		(pad "2" smd rect
			(at 0 0.9652 180)
			(size 1.397 1.143)
			(layers "F.Cu" "F.Mask" "F.Paste")
			(net "GND")
		)
	)
	(footprint ""
		(layer "F.Cu")
		(at 10.843768 -214.860378 90)
		(property "Reference" "Q243"
			(at 0 0 90)
			(layer "F.SilkS")
			(hide yes)
			(effects
				(font
					(size 1.27 1.27)
				)
			)
		)
		(property "Value" "SSM3K324R-GP"
			(at 0.127 -8.9662 90)
			(unlocked yes)
			(layer "F.Fab")
			(hide yes)
			(effects
				(font
					(size 1.016 1.016)
					(thickness 0.1524)
				)
			)
		)
		(property "Device Type" "SOT23DGS2D4H35"
			(at 0.127 -10.4902 90)
			(unlocked yes)
			(layer "F.Fab")
			(hide yes)
			(effects
				(font
					(size 1.016 1.016)
					(thickness 0.1524)
				)
			)
		)
		(duplicate_pad_numbers_are_jumpers no)
		(fp_line
			(start 1.651 -1.778)
			(end -1.651 -1.778)
			(stroke
				(width 0.1524)
				(type default)
			)
			(layer "F.SilkS")
		)
		(fp_line
			(start -1.651 -1.778)
			(end -1.651 1.778)
			(stroke
				(width 0.1524)
				(type default)
			)
			(layer "F.SilkS")
		)
		(fp_line
			(start 1.651 1.778)
			(end 1.651 -1.778)
			(stroke
				(width 0.1524)
				(type default)
			)
			(layer "F.SilkS")
		)
		(fp_line
			(start -1.651 1.778)
			(end 1.651 1.778)
			(stroke
				(width 0.1524)
				(type default)
			)
			(layer "F.SilkS")
		)
		(fp_poly
			(pts
				(xy -1.778 1.8796) (xy -1.778 -1.8796) (xy 1.778 -1.8796) (xy 1.778 1.8796)
			)
			(stroke
				(width 0)
				(type default)
			)
			(fill no)
			(layer "F.CrtYd")
		)
		(fp_poly
			(pts
				(xy -1.778 1.8796) (xy -1.778 -1.8796) (xy 1.778 -1.8796) (xy 1.778 1.8796)
			)
			(stroke
				(width 0)
				(type default)
			)
			(fill no)
			(layer "F.Fab")
		)
		(pad "D" smd custom
			(at 0 -0.9525 90)
			(size 0.1905 0.1905)
			(layers "F.Cu" "F.Mask" "F.Paste")
			(net "DRV_ACT_0_N")
			(options
				(clearance outline)
				(anchor circle)
			)
			(primitives
				(gr_poly
					(pts
						(arc
							(start -0.1778 0.5715)
							(mid -0.321484 0.511984)
							(end -0.381 0.3683)
						)
						(arc
							(start -0.381 -0.3683)
							(mid -0.321484 -0.511984)
							(end -0.1778 -0.5715)
						)
						(arc
							(start 0.1778 -0.5715)
							(mid 0.321484 -0.511984)
							(end 0.381 -0.3683)
						)
						(arc
							(start 0.381 0.3683)
							(mid 0.321484 0.511984)
							(end 0.1778 0.5715)
						)
					)
					(width 0)
					(fill yes)
				)
			)
		)
		(pad "G" smd custom
			(at -0.98425 0.9525 90)
			(size 0.1905 0.1905)
			(layers "F.Cu" "F.Mask" "F.Paste")
			(net "DRIVE_B_0_ACT")
			(options
				(clearance outline)
				(anchor circle)
			)
			(primitives
				(gr_poly
					(pts
						(arc
							(start -0.1778 0.5715)
							(mid -0.321484 0.511984)
							(end -0.381 0.3683)
						)
						(arc
							(start -0.381 -0.3683)
							(mid -0.321484 -0.511984)
							(end -0.1778 -0.5715)
						)
						(arc
							(start 0.1778 -0.5715)
							(mid 0.321484 -0.511984)
							(end 0.381 -0.3683)
						)
						(arc
							(start 0.381 0.3683)
							(mid 0.321484 0.511984)
							(end 0.1778 0.5715)
						)
					)
					(width 0)
					(fill yes)
				)
			)
		)
		(pad "S" smd custom
			(at 0.98425 0.9525 90)
			(size 0.1905 0.1905)
			(layers "F.Cu" "F.Mask" "F.Paste")
			(net "GND")
			(options
				(clearance outline)
				(anchor circle)
			)
			(primitives
				(gr_poly
					(pts
						(arc
							(start -0.1778 0.5715)
							(mid -0.321484 0.511984)
							(end -0.381 0.3683)
						)
						(arc
							(start -0.381 -0.3683)
							(mid -0.321484 -0.511984)
							(end -0.1778 -0.5715)
						)
						(arc
							(start 0.1778 -0.5715)
							(mid 0.321484 -0.511984)
							(end 0.381 -0.3683)
						)
						(arc
							(start 0.381 0.3683)
							(mid 0.321484 0.511984)
							(end 0.1778 0.5715)
						)
					)
					(width 0)
					(fill yes)
				)
			)
		)
	)
)
